(kicad_pcb
	(version 20260206)
	(generator "pcbnew")
	(generator_version "10.0")
	(general
		(thickness 1.6)
		(legacy_teardrops no)
	)
	(paper "A4")
	(title_block
		(title "04192023_DAF0TMB3IC0_F0TG_MB_C_brd_V02_OCP.brd")
		(comment 1 "Grand Teton / footprints 6876-6881 of 8354")
	)
	(layers
		(0 "F.Cu" signal "TOP")
		(4 "In1.Cu" signal "GND")
		(6 "In2.Cu" signal "IN1")
		(8 "In3.Cu" signal "GND1")
		(10 "In4.Cu" signal "IN2")
		(12 "In5.Cu" signal "GND2")
		(14 "In6.Cu" signal "IN3")
		(16 "In7.Cu" signal "GND3")
		(18 "In8.Cu" signal "VCC")
		(20 "In9.Cu" signal "VCC1")
		(22 "In10.Cu" signal "GND4")
		(24 "In11.Cu" signal "IN4")
		(26 "In12.Cu" signal "GND5")
		(28 "In13.Cu" signal "IN5")
		(30 "In14.Cu" signal "GND6")
		(32 "In15.Cu" signal "IN6")
		(34 "In16.Cu" signal "GND7")
		(2 "B.Cu" signal "BOTTOM")
		(9 "F.Adhes" user "F.Adhesive")
		(11 "B.Adhes" user "B.Adhesive")
		(13 "F.Paste" user "Package Geometry/Pastemask Top")
		(15 "B.Paste" user "Package Geometry/Pastemask Bottom")
		(5 "F.SilkS" user "Ref Des/Silkscreen Top")
		(7 "B.SilkS" user "Ref Des/Silkscreen Bottom")
		(1 "F.Mask" user "Board Geometry/Soldermask Top")
		(3 "B.Mask" user "Board Geometry/Soldermask Bottom")
		(17 "Dwgs.User" user "User.Drawings")
		(19 "Cmts.User" user "User.Comments")
		(21 "Eco1.User" user "User.Eco1")
		(23 "Eco2.User" user "User.Eco2")
		(25 "Edge.Cuts" user "Board Geometry/Outline")
		(27 "Margin" user)
		(31 "F.CrtYd" user "Package Geometry/Place Bound Top")
		(29 "B.CrtYd" user "Package Geometry/Place Bound Bottom")
		(35 "F.Fab" user "Ref Des/Assembly Top")
		(33 "B.Fab" user "Ref Des/Assembly Bottom")
	)
	(footprint ""
		(layer "B.Cu")
		(at 202.15225 -341.864442 180)
		(property "Reference" "R453"
			(at 0 0 0)
			(layer "B.SilkS")
			(hide yes)
			(effects
				(font
					(size 1.27 1.27)
				)
				(justify mirror)
			)
		)
		(property "Value" ""
			(at 0 0 0)
			(layer "B.Fab")
			(effects
				(font
					(size 1.27 1.27)
				)
				(justify mirror)
			)
		)
		(duplicate_pad_numbers_are_jumpers no)
		(fp_line
			(start 0.7874 0.4064)
			(end 0.7874 -0.4064)
			(stroke
				(width 0.1524)
				(type default)
			)
			(layer "B.SilkS")
		)
		(fp_line
			(start 0.7874 -0.4064)
			(end -0.7874 -0.4064)
			(stroke
				(width 0.1524)
				(type default)
			)
			(layer "B.SilkS")
		)
		(fp_line
			(start -0.7874 0.4064)
			(end 0.7874 0.4064)
			(stroke
				(width 0.1524)
				(type default)
			)
			(layer "B.SilkS")
		)
		(fp_line
			(start -0.7874 -0.4064)
			(end -0.7874 0.4064)
			(stroke
				(width 0.1524)
				(type default)
			)
			(layer "B.SilkS")
		)
		(fp_line
			(start 0.67945 0.3048)
			(end 0.67945 -0.305054)
			(stroke
				(width 0.1)
				(type default)
			)
			(layer "B.Fab")
		)
		(fp_line
			(start 0.67945 -0.305054)
			(end 0.12065 -0.305054)
			(stroke
				(width 0.1)
				(type default)
			)
			(layer "B.Fab")
		)
		(fp_line
			(start 0.12065 0.3048)
			(end 0.67945 0.3048)
			(stroke
				(width 0.1)
				(type default)
			)
			(layer "B.Fab")
		)
		(fp_line
			(start 0.12065 0.2794)
			(end 0.12065 0.3048)
			(stroke
				(width 0.1)
				(type default)
			)
			(layer "B.Fab")
		)
		(fp_line
			(start 0.12065 -0.2794)
			(end -0.12065 -0.2794)
			(stroke
				(width 0.1)
				(type default)
			)
			(layer "B.Fab")
		)
		(fp_line
			(start 0.12065 -0.305054)
			(end 0.12065 -0.2794)
			(stroke
				(width 0.1)
				(type default)
			)
			(layer "B.Fab")
		)
		(fp_line
			(start -0.120396 0.3048)
			(end -0.120396 0.2794)
			(stroke
				(width 0.1)
				(type default)
			)
			(layer "B.Fab")
		)
		(fp_line
			(start -0.120396 0.2794)
			(end 0.12065 0.2794)
			(stroke
				(width 0.1)
				(type default)
			)
			(layer "B.Fab")
		)
		(fp_line
			(start -0.12065 -0.2794)
			(end -0.12065 -0.3048)
			(stroke
				(width 0.1)
				(type default)
			)
			(layer "B.Fab")
		)
		(fp_line
			(start -0.12065 -0.3048)
			(end -0.67945 -0.3048)
			(stroke
				(width 0.1)
				(type default)
			)
			(layer "B.Fab")
		)
		(fp_line
			(start -0.67945 0.3048)
			(end -0.120396 0.3048)
			(stroke
				(width 0.1)
				(type default)
			)
			(layer "B.Fab")
		)
		(fp_line
			(start -0.67945 -0.3048)
			(end -0.67945 0.3048)
			(stroke
				(width 0.1)
				(type default)
			)
			(layer "B.Fab")
		)
		(pad "1" smd circle
			(at 0.40005 0)
			(size 0 0)
			(layers "B.Cu" "B.Mask" "B.Paste")
			(net "PVDD_33_S5_VCC")
		)
		(pad "2" smd circle
			(at -0.40005 0)
			(size 0 0)
			(layers "B.Cu" "B.Mask" "B.Paste")
			(net "PWRGD_PVDD33_S5")
		)
	)
	(footprint ""
		(layer "B.Cu")
		(at 118.658386 -269.307564 180)
		(property "Reference" "C2362"
			(at 0 0 0)
			(layer "B.SilkS")
			(hide yes)
			(effects
				(font
					(size 1.27 1.27)
				)
				(justify mirror)
			)
		)
		(property "Value" ""
			(at 0 0 0)
			(layer "B.Fab")
			(effects
				(font
					(size 1.27 1.27)
				)
				(justify mirror)
			)
		)
		(duplicate_pad_numbers_are_jumpers no)
		(fp_line
			(start 0.7874 0.4064)
			(end 0.7874 -0.4064)
			(stroke
				(width 0.1524)
				(type default)
			)
			(layer "B.SilkS")
		)
		(fp_line
			(start 0.7874 -0.4064)
			(end -0.7874 -0.4064)
			(stroke
				(width 0.1524)
				(type default)
			)
			(layer "B.SilkS")
		)
		(fp_line
			(start -0.7874 0.4064)
			(end 0.7874 0.4064)
			(stroke
				(width 0.1524)
				(type default)
			)
			(layer "B.SilkS")
		)
		(fp_line
			(start -0.7874 -0.4064)
			(end -0.7874 0.4064)
			(stroke
				(width 0.1524)
				(type default)
			)
			(layer "B.SilkS")
		)
		(fp_line
			(start 0.67945 0.3048)
			(end 0.67945 -0.305054)
			(stroke
				(width 0.1)
				(type default)
			)
			(layer "B.Fab")
		)
		(fp_line
			(start 0.67945 -0.305054)
			(end 0.12065 -0.305054)
			(stroke
				(width 0.1)
				(type default)
			)
			(layer "B.Fab")
		)
		(fp_line
			(start 0.12065 0.3048)
			(end 0.67945 0.3048)
			(stroke
				(width 0.1)
				(type default)
			)
			(layer "B.Fab")
		)
		(fp_line
			(start 0.12065 0.2794)
			(end 0.12065 0.3048)
			(stroke
				(width 0.1)
				(type default)
			)
			(layer "B.Fab")
		)
		(fp_line
			(start 0.12065 -0.2794)
			(end -0.12065 -0.2794)
			(stroke
				(width 0.1)
				(type default)
			)
			(layer "B.Fab")
		)
		(fp_line
			(start 0.12065 -0.305054)
			(end 0.12065 -0.2794)
			(stroke
				(width 0.1)
				(type default)
			)
			(layer "B.Fab")
		)
		(fp_line
			(start -0.120396 0.3048)
			(end -0.120396 0.2794)
			(stroke
				(width 0.1)
				(type default)
			)
			(layer "B.Fab")
		)
		(fp_line
			(start -0.120396 0.2794)
			(end 0.12065 0.2794)
			(stroke
				(width 0.1)
				(type default)
			)
			(layer "B.Fab")
		)
		(fp_line
			(start -0.12065 -0.2794)
			(end -0.12065 -0.3048)
			(stroke
				(width 0.1)
				(type default)
			)
			(layer "B.Fab")
		)
		(fp_line
			(start -0.12065 -0.3048)
			(end -0.67945 -0.3048)
			(stroke
				(width 0.1)
				(type default)
			)
			(layer "B.Fab")
		)
		(fp_line
			(start -0.67945 0.3048)
			(end -0.120396 0.3048)
			(stroke
				(width 0.1)
				(type default)
			)
			(layer "B.Fab")
		)
		(fp_line
			(start -0.67945 -0.3048)
			(end -0.67945 0.3048)
			(stroke
				(width 0.1)
				(type default)
			)
			(layer "B.Fab")
		)
		(pad "1" smd circle
			(at 0.40005 0)
			(size 0 0)
			(layers "B.Cu" "B.Mask" "B.Paste")
			(net "PVDDCR_CPU1_P1")
		)
		(pad "2" smd circle
			(at -0.40005 0)
			(size 0 0)
			(layers "B.Cu" "B.Mask" "B.Paste")
			(net "GND")
		)
	)
	(footprint ""
		(layer "B.Cu")
		(at 125.389386 -257.930396)
		(property "Reference" "C2469"
			(at 0 0 0)
			(layer "B.SilkS")
			(hide yes)
			(effects
				(font
					(size 1.27 1.27)
				)
				(justify mirror)
			)
		)
		(property "Value" ""
			(at 0 0 0)
			(layer "B.Fab")
			(effects
				(font
					(size 1.27 1.27)
				)
				(justify mirror)
			)
		)
		(duplicate_pad_numbers_are_jumpers no)
		(fp_line
			(start -0.7874 -0.4064)
			(end -0.7874 0.4064)
			(stroke
				(width 0.1524)
				(type default)
			)
			(layer "B.SilkS")
		)
		(fp_line
			(start -0.7874 0.4064)
			(end 0.7874 0.4064)
			(stroke
				(width 0.1524)
				(type default)
			)
			(layer "B.SilkS")
		)
		(fp_line
			(start 0.7874 -0.4064)
			(end -0.7874 -0.4064)
			(stroke
				(width 0.1524)
				(type default)
			)
			(layer "B.SilkS")
		)
		(fp_line
			(start 0.7874 0.4064)
			(end 0.7874 -0.4064)
			(stroke
				(width 0.1524)
				(type default)
			)
			(layer "B.SilkS")
		)
		(fp_line
			(start -0.67945 -0.3048)
			(end -0.67945 0.3048)
			(stroke
				(width 0.1)
				(type default)
			)
			(layer "B.Fab")
		)
		(fp_line
			(start -0.67945 0.3048)
			(end -0.120396 0.3048)
			(stroke
				(width 0.1)
				(type default)
			)
			(layer "B.Fab")
		)
		(fp_line
			(start -0.12065 -0.3048)
			(end -0.67945 -0.3048)
			(stroke
				(width 0.1)
				(type default)
			)
			(layer "B.Fab")
		)
		(fp_line
			(start -0.12065 -0.2794)
			(end -0.12065 -0.3048)
			(stroke
				(width 0.1)
				(type default)
			)
			(layer "B.Fab")
		)
		(fp_line
			(start -0.120396 0.2794)
			(end 0.12065 0.2794)
			(stroke
				(width 0.1)
				(type default)
			)
			(layer "B.Fab")
		)
		(fp_line
			(start -0.120396 0.3048)
			(end -0.120396 0.2794)
			(stroke
				(width 0.1)
				(type default)
			)
			(layer "B.Fab")
		)
		(fp_line
			(start 0.12065 -0.305054)
			(end 0.12065 -0.2794)
			(stroke
				(width 0.1)
				(type default)
			)
			(layer "B.Fab")
		)
		(fp_line
			(start 0.12065 -0.2794)
			(end -0.12065 -0.2794)
			(stroke
				(width 0.1)
				(type default)
			)
			(layer "B.Fab")
		)
		(fp_line
			(start 0.12065 0.2794)
			(end 0.12065 0.3048)
			(stroke
				(width 0.1)
				(type default)
			)
			(layer "B.Fab")
		)
		(fp_line
			(start 0.12065 0.3048)
			(end 0.67945 0.3048)
			(stroke
				(width 0.1)
				(type default)
			)
			(layer "B.Fab")
		)
		(fp_line
			(start 0.67945 -0.305054)
			(end 0.12065 -0.305054)
			(stroke
				(width 0.1)
				(type default)
			)
			(layer "B.Fab")
		)
		(fp_line
			(start 0.67945 0.3048)
			(end 0.67945 -0.305054)
			(stroke
				(width 0.1)
				(type default)
			)
			(layer "B.Fab")
		)
		(pad "1" smd circle
			(at 0.40005 0 180)
			(size 0 0)
			(layers "B.Cu" "B.Mask" "B.Paste")
			(net "PVDDCR_SOC_P1")
		)
		(pad "2" smd circle
			(at -0.40005 0 180)
			(size 0 0)
			(layers "B.Cu" "B.Mask" "B.Paste")
			(net "GND")
		)
	)
	(footprint ""
		(layer "B.Cu")
		(at 95.497904 -328.21753 -90)
		(property "Reference" "PC389"
			(at 7.567676 -3.601466 270)
			(unlocked yes)
			(layer "B.SilkS")
			(effects
				(font
					(size 0.7874 0.5842)
					(thickness 0.1524)
				)
				(justify left mirror)
			)
		)
		(property "Value" ""
			(at 0 0 90)
			(layer "B.Fab")
			(effects
				(font
					(size 1.27 1.27)
				)
				(justify mirror)
			)
		)
		(duplicate_pad_numbers_are_jumpers no)
		(fp_line
			(start -4.533392 2.249932)
			(end 4.533392 2.249932)
			(stroke
				(width 0.1524)
				(type default)
			)
			(layer "B.SilkS")
		)
		(fp_line
			(start 4.533392 2.249932)
			(end 4.533392 -2.249932)
			(stroke
				(width 0.1524)
				(type default)
			)
			(layer "B.SilkS")
		)
		(fp_line
			(start -4.533392 -2.249932)
			(end -4.533392 2.249932)
			(stroke
				(width 0.1524)
				(type default)
			)
			(layer "B.SilkS")
		)
		(fp_line
			(start 4.533392 -2.249932)
			(end -4.533392 -2.249932)
			(stroke
				(width 0.1524)
				(type default)
			)
			(layer "B.SilkS")
		)
		(fp_rect
			(start 5.39242 2.326132)
			(end 4.533392 -2.326132)
			(stroke
				(width 0)
				(type default)
			)
			(fill yes)
			(layer "B.SilkS")
		)
		(fp_line
			(start -3.750056 2.249932)
			(end 3.750056 2.249932)
			(stroke
				(width 0.1)
				(type default)
			)
			(layer "B.Fab")
		)
		(fp_line
			(start 3.750056 2.249932)
			(end 3.750056 -2.249932)
			(stroke
				(width 0.1)
				(type default)
			)
			(layer "B.Fab")
		)
		(fp_line
			(start -3.750056 -2.249932)
			(end -3.750056 2.249932)
			(stroke
				(width 0.1)
				(type default)
			)
			(layer "B.Fab")
		)
		(fp_line
			(start 3.750056 -2.249932)
			(end -3.750056 -2.249932)
			(stroke
				(width 0.1)
				(type default)
			)
			(layer "B.Fab")
		)
		(fp_text user "-"
			(at -4.603242 2.397252 270)
			(unlocked yes)
			(layer "B.SilkS")
			(effects
				(font
					(size 1.905 1.4224)
					(thickness 0.1524)
				)
				(justify left mirror)
			)
		)
		(fp_text user "+"
			(at 6.322314 0.786384 180)
			(unlocked yes)
			(layer "B.SilkS")
			(effects
				(font
					(size 1.905 1.4224)
					(thickness 0.1524)
				)
				(justify left mirror)
			)
		)
		(fp_text user "+"
			(at 6.322314 0.786384 180)
			(unlocked yes)
			(layer "B.Fab")
			(effects
				(font
					(size 1.905 1.4224)
					(thickness 0.1524)
				)
				(justify left mirror)
			)
		)
		(fp_text user "-"
			(at -4.8514 -0.14605 270)
			(unlocked yes)
			(layer "B.Fab")
			(effects
				(font
					(size 1.905 1.4224)
					(thickness 0.1524)
				)
				(justify left mirror)
			)
		)
		(pad "1" smd rect
			(at 3.199892 0 90)
			(size 2.413 2.8194)
			(layers "B.Cu" "B.Mask" "B.Paste")
			(net "PVDDCR_CPU1_P1")
		)
		(pad "2" smd rect
			(at -3.199892 0 90)
			(size 2.413 2.8194)
			(layers "B.Cu" "B.Mask" "B.Paste")
			(net "GND")
		)
	)
	(footprint ""
		(layer "B.Cu")
		(at 52.497228 -381.11303 180)
		(property "Reference" "C7021"
			(at -1.543304 -3.222752 0)
			(unlocked yes)
			(layer "B.SilkS")
			(effects
				(font
					(size 0.7874 0.5842)
					(thickness 0.1524)
				)
				(justify left mirror)
			)
		)
		(property "Value" ""
			(at 0 0 0)
			(layer "B.Fab")
			(effects
				(font
					(size 1.27 1.27)
				)
				(justify mirror)
			)
		)
		(duplicate_pad_numbers_are_jumpers no)
		(fp_line
			(start 4.84378 -2.150618)
			(end 4.842256 2.163064)
			(stroke
				(width 0.1524)
				(type default)
			)
			(layer "B.SilkS")
		)
		(fp_line
			(start 4.84378 -2.150618)
			(end 4.53898 -2.150618)
			(stroke
				(width 0.1524)
				(type default)
			)
			(layer "B.SilkS")
		)
		(fp_line
			(start 4.83108 2.150364)
			(end 4.447794 2.149348)
			(stroke
				(width 0.1524)
				(type default)
			)
			(layer "B.SilkS")
		)
		(fp_line
			(start 4.69138 -2.150618)
			(end 4.692396 2.161032)
			(stroke
				(width 0.1524)
				(type default)
			)
			(layer "B.SilkS")
		)
		(fp_line
			(start 4.53898 2.15011)
			(end 4.53898 -2.15011)
			(stroke
				(width 0.1524)
				(type default)
			)
			(layer "B.SilkS")
		)
		(fp_line
			(start 4.53898 -2.15011)
			(end -4.53898 -2.15011)
			(stroke
				(width 0.1524)
				(type default)
			)
			(layer "B.SilkS")
		)
		(fp_line
			(start 4.53898 -2.150618)
			(end 4.539742 2.152142)
			(stroke
				(width 0.1524)
				(type default)
			)
			(layer "B.SilkS")
		)
		(fp_line
			(start -4.53898 2.15011)
			(end 4.53898 2.15011)
			(stroke
				(width 0.1524)
				(type default)
			)
			(layer "B.SilkS")
		)
		(fp_line
			(start -4.53898 -2.15011)
			(end -4.53898 2.15011)
			(stroke
				(width 0.1524)
				(type default)
			)
			(layer "B.SilkS")
		)
		(fp_line
			(start 3.64998 2.15011)
			(end 3.64998 -2.15011)
			(stroke
				(width 0.1)
				(type default)
			)
			(layer "B.Fab")
		)
		(fp_line
			(start 3.64998 -2.15011)
			(end -3.64998 -2.15011)
			(stroke
				(width 0.1)
				(type default)
			)
			(layer "B.Fab")
		)
		(fp_line
			(start -3.64998 2.15011)
			(end 3.64998 2.15011)
			(stroke
				(width 0.1)
				(type default)
			)
			(layer "B.Fab")
		)
		(fp_line
			(start -3.64998 -2.15011)
			(end -3.64998 2.15011)
			(stroke
				(width 0.1)
				(type default)
			)
			(layer "B.Fab")
		)
		(fp_text user "+"
			(at 4.345432 -3.037078 180)
			(unlocked yes)
			(layer "B.SilkS")
			(effects
				(font
					(size 1.905 1.4224)
					(thickness 0.1524)
				)
				(justify left mirror)
			)
		)
		(fp_text user "-"
			(at -5.580634 -2.769108 180)
			(unlocked yes)
			(layer "B.SilkS")
			(effects
				(font
					(size 1.905 1.4224)
					(thickness 0.1524)
				)
				(justify left mirror)
			)
		)
		(fp_text user "+"
			(at 6.214872 -0.337058 180)
			(unlocked yes)
			(layer "B.Fab")
			(effects
				(font
					(size 1.905 1.4224)
					(thickness 0.1524)
				)
				(justify left mirror)
			)
		)
		(fp_text user "-"
			(at -4.313174 -0.094488 180)
			(unlocked yes)
			(layer "B.Fab")
			(effects
				(font
					(size 1.905 1.4224)
					(thickness 0.1524)
				)
				(justify left mirror)
			)
		)
		(pad "1" smd rect
			(at 3.199892 0)
			(size 2.413 2.8194)
			(layers "B.Cu" "B.Mask" "B.Paste")
			(net "P0V9_CPU1_RT0_2A")
		)
		(pad "2" smd rect
			(at -3.199892 0)
			(size 2.413 2.8194)
			(layers "B.Cu" "B.Mask" "B.Paste")
			(net "GND")
		)
	)
	(footprint ""
		(layer "B.Cu")
		(at 353.906074 -395.148562 90)
		(property "Reference" "C609"
			(at 0 0 90)
			(layer "B.SilkS")
			(hide yes)
			(effects
				(font
					(size 1.27 1.27)
				)
				(justify mirror)
			)
		)
		(property "Value" ""
			(at 0 0 90)
			(layer "B.Fab")
			(effects
				(font
					(size 1.27 1.27)
				)
				(justify mirror)
			)
		)
		(duplicate_pad_numbers_are_jumpers no)
		(fp_line
			(start 0.299974 -0.150114)
			(end -0.299974 -0.150114)
			(stroke
				(width 0.1)
				(type default)
			)
			(layer "B.Fab")
		)
		(fp_line
			(start -0.299974 -0.150114)
			(end -0.299974 0.150114)
			(stroke
				(width 0.1)
				(type default)
			)
			(layer "B.Fab")
		)
		(fp_line
			(start 0.299974 0.150114)
			(end 0.299974 -0.150114)
			(stroke
				(width 0.1)
				(type default)
			)
			(layer "B.Fab")
		)
		(fp_line
			(start -0.299974 0.150114)
			(end 0.299974 0.150114)
			(stroke
				(width 0.1)
				(type default)
			)
			(layer "B.Fab")
		)
		(pad "1" smd rect
			(at 0.2667 0 270)
			(size 0.3048 0.381)
			(layers "B.Cu" "B.Mask" "B.Paste")
			(net "P0V9_CPU0_RT1_2A")
		)
		(pad "2" smd rect
			(at -0.2667 0 270)
			(size 0.3048 0.381)
			(layers "B.Cu" "B.Mask" "B.Paste")
			(net "GND")
		)
	)
)
